# S9S_MB_2U (Grand Teton) — schematic netlist excerpt (pin names and nets, part order shuffled) for the footprints in the layout excerpt that follows; sources: Cadence DE-HDL packaged netlist, KiCad conversion of 03242023_DA0F0TMBIJ0_F0T_Motherboard_J_brd_V01_OCP.brd

C2266  Q_CAP  1000PF 50V 5% EMPTY  pkg 0402  page 146 : A = GPU_3V3IO_RSVD1_FFU_ISO ; B = GND
R3207  Q_RES  100K 1% CHIP  pkg 0402LF  page 160 : A = FB_BMC_ISOLATE1 ; B = GND

(kicad_pcb
	(version 20260206)
	(generator "pcbnew")
	(generator_version "10.0")
	(general
		(thickness 1.6)
		(legacy_teardrops no)
	)
	(paper "A4")
	(title_block
		(title "03242023_DA0F0TMBIJ0_F0T_Motherboard_J_brd_V01_OCP.brd")
		(comment 1 "Grand Teton / footprints 3667-3668 of 6105")
	)
	(layers
		(0 "F.Cu" signal "TOP")
		(4 "In1.Cu" signal "GND")
		(6 "In2.Cu" signal "IN1")
		(8 "In3.Cu" signal "GND1")
		(10 "In4.Cu" signal "IN2")
		(12 "In5.Cu" signal "GND2")
		(14 "In6.Cu" signal "IN3")
		(16 "In7.Cu" signal "GND3")
		(18 "In8.Cu" signal "VCC")
		(20 "In9.Cu" signal "VCC1")
		(22 "In10.Cu" signal "GND4")
		(24 "In11.Cu" signal "IN4")
		(26 "In12.Cu" signal "GND5")
		(28 "In13.Cu" signal "IN5")
		(30 "In14.Cu" signal "GND6")
		(32 "In15.Cu" signal "IN6")
		(34 "In16.Cu" signal "GND7")
		(2 "B.Cu" signal "BOTTOM")
		(9 "F.Adhes" user "F.Adhesive")
		(11 "B.Adhes" user "B.Adhesive")
		(13 "F.Paste" user "Package Geometry/Pastemask Top")
		(15 "B.Paste" user "Package Geometry/Pastemask Bottom")
		(5 "F.SilkS" user "Ref Des/Silkscreen Top")
		(7 "B.SilkS" user "Ref Des/Silkscreen Bottom")
		(1 "F.Mask" user "Board Geometry/Soldermask Top")
		(3 "B.Mask" user "Board Geometry/Soldermask Bottom")
		(17 "Dwgs.User" user "User.Drawings")
		(19 "Cmts.User" user "User.Comments")
		(21 "Eco1.User" user "User.Eco1")
		(23 "Eco2.User" user "User.Eco2")
		(25 "Edge.Cuts" user "Board Geometry/Outline")
		(27 "Margin" user)
		(31 "F.CrtYd" user "Package Geometry/Place Bound Top")
		(29 "B.CrtYd" user "Package Geometry/Place Bound Bottom")
		(35 "F.Fab" user "Ref Des/Assembly Top")
		(33 "B.Fab" user "Ref Des/Assembly Bottom")
	)
	(footprint ""
		(layer "F.Cu")
		(at 309.57774 -430.73701 -90)
		(property "Reference" "C2266"
			(at 0 0 270)
			(layer "F.SilkS")
			(hide yes)
			(effects
				(font
					(size 1.27 1.27)
				)
			)
		)
		(property "Value" ""
			(at 0 0 270)
			(layer "F.Fab")
			(effects
				(font
					(size 1.27 1.27)
				)
			)
		)
		(duplicate_pad_numbers_are_jumpers no)
		(fp_line
			(start -0.7874 0.4064)
			(end -0.7874 -0.4064)
			(stroke
				(width 0.1524)
				(type default)
			)
			(layer "F.SilkS")
		)
		(fp_line
			(start 0.7874 0.4064)
			(end -0.7874 0.4064)
			(stroke
				(width 0.1524)
				(type default)
			)
			(layer "F.SilkS")
		)
		(fp_line
			(start -0.7874 -0.4064)
			(end 0.7874 -0.4064)
			(stroke
				(width 0.1524)
				(type default)
			)
			(layer "F.SilkS")
		)
		(fp_line
			(start 0.7874 -0.4064)
			(end 0.7874 0.4064)
			(stroke
				(width 0.1524)
				(type default)
			)
			(layer "F.SilkS")
		)
		(fp_line
			(start -0.67945 0.3048)
			(end -0.67945 -0.305054)
			(stroke
				(width 0.1)
				(type default)
			)
			(layer "F.Fab")
		)
		(fp_line
			(start -0.12065 0.3048)
			(end -0.67945 0.3048)
			(stroke
				(width 0.1)
				(type default)
			)
			(layer "F.Fab")
		)
		(fp_line
			(start 0.120396 0.3048)
			(end 0.120396 0.2794)
			(stroke
				(width 0.1)
				(type default)
			)
			(layer "F.Fab")
		)
		(fp_line
			(start 0.67945 0.3048)
			(end 0.120396 0.3048)
			(stroke
				(width 0.1)
				(type default)
			)
			(layer "F.Fab")
		)
		(fp_line
			(start -0.12065 0.2794)
			(end -0.12065 0.3048)
			(stroke
				(width 0.1)
				(type default)
			)
			(layer "F.Fab")
		)
		(fp_line
			(start 0.120396 0.2794)
			(end -0.12065 0.2794)
			(stroke
				(width 0.1)
				(type default)
			)
			(layer "F.Fab")
		)
		(fp_line
			(start -0.12065 -0.2794)
			(end 0.12065 -0.2794)
			(stroke
				(width 0.1)
				(type default)
			)
			(layer "F.Fab")
		)
		(fp_line
			(start 0.12065 -0.2794)
			(end 0.12065 -0.3048)
			(stroke
				(width 0.1)
				(type default)
			)
			(layer "F.Fab")
		)
		(fp_line
			(start 0.12065 -0.3048)
			(end 0.67945 -0.3048)
			(stroke
				(width 0.1)
				(type default)
			)
			(layer "F.Fab")
		)
		(fp_line
			(start 0.67945 -0.3048)
			(end 0.67945 0.3048)
			(stroke
				(width 0.1)
				(type default)
			)
			(layer "F.Fab")
		)
		(fp_line
			(start -0.67945 -0.305054)
			(end -0.12065 -0.305054)
			(stroke
				(width 0.1)
				(type default)
			)
			(layer "F.Fab")
		)
		(fp_line
			(start -0.12065 -0.305054)
			(end -0.12065 -0.2794)
			(stroke
				(width 0.1)
				(type default)
			)
			(layer "F.Fab")
		)
		(pad "1" smd circle
			(at -0.40005 0 270)
			(size 0 0)
			(layers "F.Cu" "F.Mask" "F.Paste")
			(net "GPU_3V3IO_RSVD1_FFU_ISO")
		)
		(pad "2" smd circle
			(at 0.40005 0 270)
			(size 0 0)
			(layers "F.Cu" "F.Mask" "F.Paste")
			(net "GND")
		)
	)
	(footprint ""
		(layer "F.Cu")
		(at 152.96388 -130.774948)
		(property "Reference" "R3207"
			(at 0 0 0)
			(layer "F.SilkS")
			(hide yes)
			(effects
				(font
					(size 1.27 1.27)
				)
			)
		)
		(property "Value" ""
			(at 0 0 0)
			(layer "F.Fab")
			(effects
				(font
					(size 1.27 1.27)
				)
			)
		)
		(duplicate_pad_numbers_are_jumpers no)
		(fp_line
			(start -0.7874 -0.4064)
			(end 0.7874 -0.4064)
			(stroke
				(width 0.1524)
				(type default)
			)
			(layer "F.SilkS")
		)
		(fp_line
			(start -0.7874 0.4064)
			(end -0.7874 -0.4064)
			(stroke
				(width 0.1524)
				(type default)
			)
			(layer "F.SilkS")
		)
		(fp_line
			(start 0.7874 -0.4064)
			(end 0.7874 0.4064)
			(stroke
				(width 0.1524)
				(type default)
			)
			(layer "F.SilkS")
		)
		(fp_line
			(start 0.7874 0.4064)
			(end -0.7874 0.4064)
			(stroke
				(width 0.1524)
				(type default)
			)
			(layer "F.SilkS")
		)
		(fp_line
			(start -0.67945 -0.305054)
			(end -0.12065 -0.305054)
			(stroke
				(width 0.1)
				(type default)
			)
			(layer "F.Fab")
		)
		(fp_line
			(start -0.67945 0.3048)
			(end -0.67945 -0.305054)
			(stroke
				(width 0.1)
				(type default)
			)
			(layer "F.Fab")
		)
		(fp_line
			(start -0.12065 -0.305054)
			(end -0.12065 -0.2794)
			(stroke
				(width 0.1)
				(type default)
			)
			(layer "F.Fab")
		)
		(fp_line
			(start -0.12065 -0.2794)
			(end 0.12065 -0.2794)
			(stroke
				(width 0.1)
				(type default)
			)
			(layer "F.Fab")
		)
		(fp_line
			(start -0.12065 0.2794)
			(end -0.12065 0.3048)
			(stroke
				(width 0.1)
				(type default)
			)
			(layer "F.Fab")
		)
		(fp_line
			(start -0.12065 0.3048)
			(end -0.67945 0.3048)
			(stroke
				(width 0.1)
				(type default)
			)
			(layer "F.Fab")
		)
		(fp_line
			(start 0.120396 0.2794)
			(end -0.12065 0.2794)
			(stroke
				(width 0.1)
				(type default)
			)
			(layer "F.Fab")
		)
		(fp_line
			(start 0.120396 0.3048)
			(end 0.120396 0.2794)
			(stroke
				(width 0.1)
				(type default)
			)
			(layer "F.Fab")
		)
		(fp_line
			(start 0.12065 -0.3048)
			(end 0.67945 -0.3048)
			(stroke
				(width 0.1)
				(type default)
			)
			(layer "F.Fab")
		)
		(fp_line
			(start 0.12065 -0.2794)
			(end 0.12065 -0.3048)
			(stroke
				(width 0.1)
				(type default)
			)
			(layer "F.Fab")
		)
		(fp_line
			(start 0.67945 -0.3048)
			(end 0.67945 0.3048)
			(stroke
				(width 0.1)
				(type default)
			)
			(layer "F.Fab")
		)
		(fp_line
			(start 0.67945 0.3048)
			(end 0.120396 0.3048)
			(stroke
				(width 0.1)
				(type default)
			)
			(layer "F.Fab")
		)
		(pad "1" smd circle
			(at -0.40005 0)
			(size 0 0)
			(layers "F.Cu" "F.Mask" "F.Paste")
			(net "FB_BMC_ISOLATE1")
		)
		(pad "2" smd circle
			(at 0.40005 0)
			(size 0 0)
			(layers "F.Cu" "F.Mask" "F.Paste")
			(net "GND")
		)
	)
)
